(kicad_pcb
	(version 20260206)
	(generator "pcbnew")
	(generator_version "10.0")
	(general
		(thickness 1.6)
		(legacy_teardrops no)
	)
	(paper "A4")
	(title_block
		(title "03242023_DA0F0TMBIJ0_F0T_Motherboard_J_brd_V01_OCP.brd")
		(comment 1 "Grand Teton / footprints 4410-4415 of 6105")
	)
	(layers
		(0 "F.Cu" signal "TOP")
		(4 "In1.Cu" signal "GND")
		(6 "In2.Cu" signal "IN1")
		(8 "In3.Cu" signal "GND1")
		(10 "In4.Cu" signal "IN2")
		(12 "In5.Cu" signal "GND2")
		(14 "In6.Cu" signal "IN3")
		(16 "In7.Cu" signal "GND3")
		(18 "In8.Cu" signal "VCC")
		(20 "In9.Cu" signal "VCC1")
		(22 "In10.Cu" signal "GND4")
		(24 "In11.Cu" signal "IN4")
		(26 "In12.Cu" signal "GND5")
		(28 "In13.Cu" signal "IN5")
		(30 "In14.Cu" signal "GND6")
		(32 "In15.Cu" signal "IN6")
		(34 "In16.Cu" signal "GND7")
		(2 "B.Cu" signal "BOTTOM")
		(9 "F.Adhes" user "F.Adhesive")
		(11 "B.Adhes" user "B.Adhesive")
		(13 "F.Paste" user "Package Geometry/Pastemask Top")
		(15 "B.Paste" user "Package Geometry/Pastemask Bottom")
		(5 "F.SilkS" user "Ref Des/Silkscreen Top")
		(7 "B.SilkS" user "Ref Des/Silkscreen Bottom")
		(1 "F.Mask" user "Board Geometry/Soldermask Top")
		(3 "B.Mask" user "Board Geometry/Soldermask Bottom")
		(17 "Dwgs.User" user "User.Drawings")
		(19 "Cmts.User" user "User.Comments")
		(21 "Eco1.User" user "User.Eco1")
		(23 "Eco2.User" user "User.Eco2")
		(25 "Edge.Cuts" user "Board Geometry/Outline")
		(27 "Margin" user)
		(31 "F.CrtYd" user "Package Geometry/Place Bound Top")
		(29 "B.CrtYd" user "Package Geometry/Place Bound Bottom")
		(35 "F.Fab" user "Ref Des/Assembly Top")
		(33 "B.Fab" user "Ref Des/Assembly Bottom")
	)
	(footprint ""
		(layer "B.Cu")
		(at 279.119584 -193.669666 -90)
		(property "Reference" "R1391"
			(at 0 0 90)
			(layer "B.SilkS")
			(hide yes)
			(effects
				(font
					(size 1.27 1.27)
				)
				(justify mirror)
			)
		)
		(property "Value" ""
			(at 0 0 90)
			(layer "B.Fab")
			(effects
				(font
					(size 1.27 1.27)
				)
				(justify mirror)
			)
		)
		(duplicate_pad_numbers_are_jumpers no)
		(fp_line
			(start -0.7874 0.4064)
			(end 0.7874 0.4064)
			(stroke
				(width 0.1524)
				(type default)
			)
			(layer "B.SilkS")
		)
		(fp_line
			(start 0.7874 0.4064)
			(end 0.7874 -0.4064)
			(stroke
				(width 0.1524)
				(type default)
			)
			(layer "B.SilkS")
		)
		(fp_line
			(start -0.7874 -0.4064)
			(end -0.7874 0.4064)
			(stroke
				(width 0.1524)
				(type default)
			)
			(layer "B.SilkS")
		)
		(fp_line
			(start 0.7874 -0.4064)
			(end -0.7874 -0.4064)
			(stroke
				(width 0.1524)
				(type default)
			)
			(layer "B.SilkS")
		)
		(fp_line
			(start -0.67945 0.3048)
			(end -0.120396 0.3048)
			(stroke
				(width 0.1)
				(type default)
			)
			(layer "B.Fab")
		)
		(fp_line
			(start -0.120396 0.3048)
			(end -0.120396 0.2794)
			(stroke
				(width 0.1)
				(type default)
			)
			(layer "B.Fab")
		)
		(fp_line
			(start 0.12065 0.3048)
			(end 0.67945 0.3048)
			(stroke
				(width 0.1)
				(type default)
			)
			(layer "B.Fab")
		)
		(fp_line
			(start 0.67945 0.3048)
			(end 0.67945 -0.305054)
			(stroke
				(width 0.1)
				(type default)
			)
			(layer "B.Fab")
		)
		(fp_line
			(start -0.120396 0.2794)
			(end 0.12065 0.2794)
			(stroke
				(width 0.1)
				(type default)
			)
			(layer "B.Fab")
		)
		(fp_line
			(start 0.12065 0.2794)
			(end 0.12065 0.3048)
			(stroke
				(width 0.1)
				(type default)
			)
			(layer "B.Fab")
		)
		(fp_line
			(start -0.12065 -0.2794)
			(end -0.12065 -0.3048)
			(stroke
				(width 0.1)
				(type default)
			)
			(layer "B.Fab")
		)
		(fp_line
			(start 0.12065 -0.2794)
			(end -0.12065 -0.2794)
			(stroke
				(width 0.1)
				(type default)
			)
			(layer "B.Fab")
		)
		(fp_line
			(start -0.67945 -0.3048)
			(end -0.67945 0.3048)
			(stroke
				(width 0.1)
				(type default)
			)
			(layer "B.Fab")
		)
		(fp_line
			(start -0.12065 -0.3048)
			(end -0.67945 -0.3048)
			(stroke
				(width 0.1)
				(type default)
			)
			(layer "B.Fab")
		)
		(fp_line
			(start 0.12065 -0.305054)
			(end 0.12065 -0.2794)
			(stroke
				(width 0.1)
				(type default)
			)
			(layer "B.Fab")
		)
		(fp_line
			(start 0.67945 -0.305054)
			(end 0.12065 -0.305054)
			(stroke
				(width 0.1)
				(type default)
			)
			(layer "B.Fab")
		)
		(pad "1" smd circle
			(at 0.40005 0 90)
			(size 0 0)
			(layers "B.Cu" "B.Mask" "B.Paste")
			(net "GND")
		)
		(pad "2" smd circle
			(at -0.40005 0 90)
			(size 0 0)
			(layers "B.Cu" "B.Mask" "B.Paste")
			(net "FM_S3M_CPU0_LVC1_GPIO_2")
		)
	)
	(footprint ""
		(layer "B.Cu")
		(at 105.679494 -255.8542 -90)
		(property "Reference" "C321"
			(at 0 0 90)
			(layer "B.SilkS")
			(hide yes)
			(effects
				(font
					(size 1.27 1.27)
				)
				(justify mirror)
			)
		)
		(property "Value" ""
			(at 0 0 90)
			(layer "B.Fab")
			(effects
				(font
					(size 1.27 1.27)
				)
				(justify mirror)
			)
		)
		(duplicate_pad_numbers_are_jumpers no)
		(fp_line
			(start -1.524 0.762)
			(end 1.524 0.762)
			(stroke
				(width 0.1524)
				(type default)
			)
			(layer "B.SilkS")
		)
		(fp_line
			(start 1.524 0.762)
			(end 1.524 -0.762)
			(stroke
				(width 0.1524)
				(type default)
			)
			(layer "B.SilkS")
		)
		(fp_line
			(start -1.524 -0.762)
			(end -1.524 0.762)
			(stroke
				(width 0.1524)
				(type default)
			)
			(layer "B.SilkS")
		)
		(fp_line
			(start 1.524 -0.762)
			(end -1.524 -0.762)
			(stroke
				(width 0.1524)
				(type default)
			)
			(layer "B.SilkS")
		)
		(fp_line
			(start -1.1049 0.724916)
			(end -1.1049 -0.724916)
			(stroke
				(width 0.1)
				(type default)
			)
			(layer "B.Fab")
		)
		(fp_line
			(start 1.1049 0.724916)
			(end -1.1049 0.724916)
			(stroke
				(width 0.1)
				(type default)
			)
			(layer "B.Fab")
		)
		(fp_line
			(start -1.1049 -0.724916)
			(end 1.1049 -0.724916)
			(stroke
				(width 0.1)
				(type default)
			)
			(layer "B.Fab")
		)
		(fp_line
			(start 1.1049 -0.724916)
			(end 1.1049 0.724916)
			(stroke
				(width 0.1)
				(type default)
			)
			(layer "B.Fab")
		)
		(pad "1" smd rect
			(at 0.889 0 270)
			(size 1.016 1.27)
			(layers "B.Cu" "B.Mask" "B.Paste")
			(net "PVCCIN_CPU1")
		)
		(pad "2" smd rect
			(at -0.889 0 270)
			(size 1.016 1.27)
			(layers "B.Cu" "B.Mask" "B.Paste")
			(net "GND")
		)
	)
	(footprint ""
		(layer "B.Cu")
		(at 204.133958 -192.95491)
		(property "Reference" "C541"
			(at 0 0 0)
			(layer "B.SilkS")
			(hide yes)
			(effects
				(font
					(size 1.27 1.27)
				)
				(justify mirror)
			)
		)
		(property "Value" ""
			(at 0 0 0)
			(layer "B.Fab")
			(effects
				(font
					(size 1.27 1.27)
				)
				(justify mirror)
			)
		)
		(duplicate_pad_numbers_are_jumpers no)
		(fp_line
			(start -0.7874 -0.4064)
			(end -0.7874 0.4064)
			(stroke
				(width 0.1524)
				(type default)
			)
			(layer "B.SilkS")
		)
		(fp_line
			(start -0.7874 0.4064)
			(end 0.7874 0.4064)
			(stroke
				(width 0.1524)
				(type default)
			)
			(layer "B.SilkS")
		)
		(fp_line
			(start 0.7874 -0.4064)
			(end -0.7874 -0.4064)
			(stroke
				(width 0.1524)
				(type default)
			)
			(layer "B.SilkS")
		)
		(fp_line
			(start 0.7874 0.4064)
			(end 0.7874 -0.4064)
			(stroke
				(width 0.1524)
				(type default)
			)
			(layer "B.SilkS")
		)
		(fp_line
			(start -0.67945 -0.3048)
			(end -0.67945 0.3048)
			(stroke
				(width 0.1)
				(type default)
			)
			(layer "B.Fab")
		)
		(fp_line
			(start -0.67945 0.3048)
			(end -0.120396 0.3048)
			(stroke
				(width 0.1)
				(type default)
			)
			(layer "B.Fab")
		)
		(fp_line
			(start -0.12065 -0.3048)
			(end -0.67945 -0.3048)
			(stroke
				(width 0.1)
				(type default)
			)
			(layer "B.Fab")
		)
		(fp_line
			(start -0.12065 -0.2794)
			(end -0.12065 -0.3048)
			(stroke
				(width 0.1)
				(type default)
			)
			(layer "B.Fab")
		)
		(fp_line
			(start -0.120396 0.2794)
			(end 0.12065 0.2794)
			(stroke
				(width 0.1)
				(type default)
			)
			(layer "B.Fab")
		)
		(fp_line
			(start -0.120396 0.3048)
			(end -0.120396 0.2794)
			(stroke
				(width 0.1)
				(type default)
			)
			(layer "B.Fab")
		)
		(fp_line
			(start 0.12065 -0.305054)
			(end 0.12065 -0.2794)
			(stroke
				(width 0.1)
				(type default)
			)
			(layer "B.Fab")
		)
		(fp_line
			(start 0.12065 -0.2794)
			(end -0.12065 -0.2794)
			(stroke
				(width 0.1)
				(type default)
			)
			(layer "B.Fab")
		)
		(fp_line
			(start 0.12065 0.2794)
			(end 0.12065 0.3048)
			(stroke
				(width 0.1)
				(type default)
			)
			(layer "B.Fab")
		)
		(fp_line
			(start 0.12065 0.3048)
			(end 0.67945 0.3048)
			(stroke
				(width 0.1)
				(type default)
			)
			(layer "B.Fab")
		)
		(fp_line
			(start 0.67945 -0.305054)
			(end 0.12065 -0.305054)
			(stroke
				(width 0.1)
				(type default)
			)
			(layer "B.Fab")
		)
		(fp_line
			(start 0.67945 0.3048)
			(end 0.67945 -0.305054)
			(stroke
				(width 0.1)
				(type default)
			)
			(layer "B.Fab")
		)
		(pad "1" smd circle
			(at 0.40005 0 180)
			(size 0 0)
			(layers "B.Cu" "B.Mask" "B.Paste")
			(net "P3V3_AUX")
		)
		(pad "2" smd circle
			(at -0.40005 0 180)
			(size 0 0)
			(layers "B.Cu" "B.Mask" "B.Paste")
			(net "GND")
		)
	)
	(footprint ""
		(layer "B.Cu")
		(at 150.387304 -190.36411 90)
		(property "Reference" "R672"
			(at 0 0 90)
			(layer "B.SilkS")
			(hide yes)
			(effects
				(font
					(size 1.27 1.27)
				)
				(justify mirror)
			)
		)
		(property "Value" ""
			(at 0 0 90)
			(layer "B.Fab")
			(effects
				(font
					(size 1.27 1.27)
				)
				(justify mirror)
			)
		)
		(duplicate_pad_numbers_are_jumpers no)
		(fp_line
			(start 0.7874 -0.4064)
			(end -0.7874 -0.4064)
			(stroke
				(width 0.1524)
				(type default)
			)
			(layer "B.SilkS")
		)
		(fp_line
			(start -0.7874 -0.4064)
			(end -0.7874 0.4064)
			(stroke
				(width 0.1524)
				(type default)
			)
			(layer "B.SilkS")
		)
		(fp_line
			(start 0.7874 0.4064)
			(end 0.7874 -0.4064)
			(stroke
				(width 0.1524)
				(type default)
			)
			(layer "B.SilkS")
		)
		(fp_line
			(start -0.7874 0.4064)
			(end 0.7874 0.4064)
			(stroke
				(width 0.1524)
				(type default)
			)
			(layer "B.SilkS")
		)
		(fp_line
			(start 0.67945 -0.305054)
			(end 0.12065 -0.305054)
			(stroke
				(width 0.1)
				(type default)
			)
			(layer "B.Fab")
		)
		(fp_line
			(start 0.12065 -0.305054)
			(end 0.12065 -0.2794)
			(stroke
				(width 0.1)
				(type default)
			)
			(layer "B.Fab")
		)
		(fp_line
			(start -0.12065 -0.3048)
			(end -0.67945 -0.3048)
			(stroke
				(width 0.1)
				(type default)
			)
			(layer "B.Fab")
		)
		(fp_line
			(start -0.67945 -0.3048)
			(end -0.67945 0.3048)
			(stroke
				(width 0.1)
				(type default)
			)
			(layer "B.Fab")
		)
		(fp_line
			(start 0.12065 -0.2794)
			(end -0.12065 -0.2794)
			(stroke
				(width 0.1)
				(type default)
			)
			(layer "B.Fab")
		)
		(fp_line
			(start -0.12065 -0.2794)
			(end -0.12065 -0.3048)
			(stroke
				(width 0.1)
				(type default)
			)
			(layer "B.Fab")
		)
		(fp_line
			(start 0.12065 0.2794)
			(end 0.12065 0.3048)
			(stroke
				(width 0.1)
				(type default)
			)
			(layer "B.Fab")
		)
		(fp_line
			(start -0.120396 0.2794)
			(end 0.12065 0.2794)
			(stroke
				(width 0.1)
				(type default)
			)
			(layer "B.Fab")
		)
		(fp_line
			(start 0.67945 0.3048)
			(end 0.67945 -0.305054)
			(stroke
				(width 0.1)
				(type default)
			)
			(layer "B.Fab")
		)
		(fp_line
			(start 0.12065 0.3048)
			(end 0.67945 0.3048)
			(stroke
				(width 0.1)
				(type default)
			)
			(layer "B.Fab")
		)
		(fp_line
			(start -0.120396 0.3048)
			(end -0.120396 0.2794)
			(stroke
				(width 0.1)
				(type default)
			)
			(layer "B.Fab")
		)
		(fp_line
			(start -0.67945 0.3048)
			(end -0.120396 0.3048)
			(stroke
				(width 0.1)
				(type default)
			)
			(layer "B.Fab")
		)
		(pad "1" smd circle
			(at 0.40005 0 270)
			(size 0 0)
			(layers "B.Cu" "B.Mask" "B.Paste")
			(net "I3C_SPD_DDREFGH_CPU1_SCL")
		)
		(pad "2" smd circle
			(at -0.40005 0 270)
			(size 0 0)
			(layers "B.Cu" "B.Mask" "B.Paste")
			(net "I3C_SPD_DDREFGH_CPU1_R_SCL")
		)
	)
	(footprint ""
		(layer "B.Cu")
		(at 184.059576 -13.60043 -90)
		(property "Reference" "R599"
			(at 0 0 90)
			(layer "B.SilkS")
			(hide yes)
			(effects
				(font
					(size 1.27 1.27)
				)
				(justify mirror)
			)
		)
		(property "Value" ""
			(at 0 0 90)
			(layer "B.Fab")
			(effects
				(font
					(size 1.27 1.27)
				)
				(justify mirror)
			)
		)
		(duplicate_pad_numbers_are_jumpers no)
		(fp_line
			(start -0.7874 0.4064)
			(end 0.7874 0.4064)
			(stroke
				(width 0.1524)
				(type default)
			)
			(layer "B.SilkS")
		)
		(fp_line
			(start 0.7874 0.4064)
			(end 0.7874 -0.4064)
			(stroke
				(width 0.1524)
				(type default)
			)
			(layer "B.SilkS")
		)
		(fp_line
			(start -0.7874 -0.4064)
			(end -0.7874 0.4064)
			(stroke
				(width 0.1524)
				(type default)
			)
			(layer "B.SilkS")
		)
		(fp_line
			(start 0.7874 -0.4064)
			(end -0.7874 -0.4064)
			(stroke
				(width 0.1524)
				(type default)
			)
			(layer "B.SilkS")
		)
		(fp_line
			(start -0.67945 0.3048)
			(end -0.120396 0.3048)
			(stroke
				(width 0.1)
				(type default)
			)
			(layer "B.Fab")
		)
		(fp_line
			(start -0.120396 0.3048)
			(end -0.120396 0.2794)
			(stroke
				(width 0.1)
				(type default)
			)
			(layer "B.Fab")
		)
		(fp_line
			(start 0.12065 0.3048)
			(end 0.67945 0.3048)
			(stroke
				(width 0.1)
				(type default)
			)
			(layer "B.Fab")
		)
		(fp_line
			(start 0.67945 0.3048)
			(end 0.67945 -0.305054)
			(stroke
				(width 0.1)
				(type default)
			)
			(layer "B.Fab")
		)
		(fp_line
			(start -0.120396 0.2794)
			(end 0.12065 0.2794)
			(stroke
				(width 0.1)
				(type default)
			)
			(layer "B.Fab")
		)
		(fp_line
			(start 0.12065 0.2794)
			(end 0.12065 0.3048)
			(stroke
				(width 0.1)
				(type default)
			)
			(layer "B.Fab")
		)
		(fp_line
			(start -0.12065 -0.2794)
			(end -0.12065 -0.3048)
			(stroke
				(width 0.1)
				(type default)
			)
			(layer "B.Fab")
		)
		(fp_line
			(start 0.12065 -0.2794)
			(end -0.12065 -0.2794)
			(stroke
				(width 0.1)
				(type default)
			)
			(layer "B.Fab")
		)
		(fp_line
			(start -0.67945 -0.3048)
			(end -0.67945 0.3048)
			(stroke
				(width 0.1)
				(type default)
			)
			(layer "B.Fab")
		)
		(fp_line
			(start -0.12065 -0.3048)
			(end -0.67945 -0.3048)
			(stroke
				(width 0.1)
				(type default)
			)
			(layer "B.Fab")
		)
		(fp_line
			(start 0.12065 -0.305054)
			(end 0.12065 -0.2794)
			(stroke
				(width 0.1)
				(type default)
			)
			(layer "B.Fab")
		)
		(fp_line
			(start 0.67945 -0.305054)
			(end 0.12065 -0.305054)
			(stroke
				(width 0.1)
				(type default)
			)
			(layer "B.Fab")
		)
		(pad "1" smd circle
			(at 0.40005 0 90)
			(size 0 0)
			(layers "B.Cu" "B.Mask" "B.Paste")
			(net "I3C_SPD_DDREFGH_CPU1_BMC_R_SCL")
		)
		(pad "2" smd circle
			(at -0.40005 0 90)
			(size 0 0)
			(layers "B.Cu" "B.Mask" "B.Paste")
			(net "I3C_SPD_DDREFGH_CPU1_BMC_SCL")
		)
	)
	(footprint ""
		(layer "B.Cu")
		(at 152.9969 -13.762228 90)
		(property "Reference" "R2416"
			(at 0 0 90)
			(layer "B.SilkS")
			(hide yes)
			(effects
				(font
					(size 1.27 1.27)
				)
				(justify mirror)
			)
		)
		(property "Value" ""
			(at 0 0 90)
			(layer "B.Fab")
			(effects
				(font
					(size 1.27 1.27)
				)
				(justify mirror)
			)
		)
		(duplicate_pad_numbers_are_jumpers no)
		(fp_line
			(start 0.7874 -0.4064)
			(end -0.7874 -0.4064)
			(stroke
				(width 0.1524)
				(type default)
			)
			(layer "B.SilkS")
		)
		(fp_line
			(start -0.7874 -0.4064)
			(end -0.7874 0.4064)
			(stroke
				(width 0.1524)
				(type default)
			)
			(layer "B.SilkS")
		)
		(fp_line
			(start 0.7874 0.4064)
			(end 0.7874 -0.4064)
			(stroke
				(width 0.1524)
				(type default)
			)
			(layer "B.SilkS")
		)
		(fp_line
			(start -0.7874 0.4064)
			(end 0.7874 0.4064)
			(stroke
				(width 0.1524)
				(type default)
			)
			(layer "B.SilkS")
		)
		(fp_line
			(start 0.67945 -0.305054)
			(end 0.12065 -0.305054)
			(stroke
				(width 0.1)
				(type default)
			)
			(layer "B.Fab")
		)
		(fp_line
			(start 0.12065 -0.305054)
			(end 0.12065 -0.2794)
			(stroke
				(width 0.1)
				(type default)
			)
			(layer "B.Fab")
		)
		(fp_line
			(start -0.12065 -0.3048)
			(end -0.67945 -0.3048)
			(stroke
				(width 0.1)
				(type default)
			)
			(layer "B.Fab")
		)
		(fp_line
			(start -0.67945 -0.3048)
			(end -0.67945 0.3048)
			(stroke
				(width 0.1)
				(type default)
			)
			(layer "B.Fab")
		)
		(fp_line
			(start 0.12065 -0.2794)
			(end -0.12065 -0.2794)
			(stroke
				(width 0.1)
				(type default)
			)
			(layer "B.Fab")
		)
		(fp_line
			(start -0.12065 -0.2794)
			(end -0.12065 -0.3048)
			(stroke
				(width 0.1)
				(type default)
			)
			(layer "B.Fab")
		)
		(fp_line
			(start 0.12065 0.2794)
			(end 0.12065 0.3048)
			(stroke
				(width 0.1)
				(type default)
			)
			(layer "B.Fab")
		)
		(fp_line
			(start -0.120396 0.2794)
			(end 0.12065 0.2794)
			(stroke
				(width 0.1)
				(type default)
			)
			(layer "B.Fab")
		)
		(fp_line
			(start 0.67945 0.3048)
			(end 0.67945 -0.305054)
			(stroke
				(width 0.1)
				(type default)
			)
			(layer "B.Fab")
		)
		(fp_line
			(start 0.12065 0.3048)
			(end 0.67945 0.3048)
			(stroke
				(width 0.1)
				(type default)
			)
			(layer "B.Fab")
		)
		(fp_line
			(start -0.120396 0.3048)
			(end -0.120396 0.2794)
			(stroke
				(width 0.1)
				(type default)
			)
			(layer "B.Fab")
		)
		(fp_line
			(start -0.67945 0.3048)
			(end -0.120396 0.3048)
			(stroke
				(width 0.1)
				(type default)
			)
			(layer "B.Fab")
		)
		(pad "1" smd circle
			(at 0.40005 0 270)
			(size 0 0)
			(layers "B.Cu" "B.Mask" "B.Paste")
			(net "SMB_1_BMC_GPU_SDA")
		)
		(pad "2" smd circle
			(at -0.40005 0 270)
			(size 0 0)
			(layers "B.Cu" "B.Mask" "B.Paste")
			(net "SMB_PCIE3_3V3AUX_SDA_R")
		)
	)
)
